# Stackup_F0T_Fan_BP_6L_1p6mm_IT-170GT_RTF_Rev0p1_20211021.xls — Stackup (pcb-stackup)
| STACKUP |  |  |  | Target Z (ohms) - MicroStrip |  |  |  |  | 50 | Breakout |
|  |  |  |  | Target Z (ohms) - StripLine |  |  |  |  | 50 |  |
|  |  |  |  | Z tolerance |  |  |  |  | 0.1 |  |
|  |  |  |  | Z Type |  |  |  |  | Single | Single |
| Layer# | Material | Description |  | Copper Weight (oz) | Thickness (mil) | Tolerance (mil) | Glass Fabric | Er | Width | Width |
|  |  |  | Soldermask |  | 0.6 |  |  | 3.8 |  |  |
| 1 |  |  | TOP | 0.5+plating | 1.95 |  |  |  | 10.5 | 4 |
|  | IT-170GT |  | PP |  | 6 | ±0.984 | Vendor Define | 3.89 |  |  |
| 2 |  |  | GND | 2 (RTF) | 2.6 |  |  |  |  |  |
|  | IT-170GT |  | CORE |  | 6 | ±0.984 | 1080x2 | 3.89 |  |  |
| 3 |  |  | IN1 | 1 (RTF) | 1.3 |  |  |  | 8.5 | 4 |
|  | IT-170GT |  | PP |  | 26.1 | ±2.52 | Vendor Define | 4.08 |  |  |
| 4 |  |  | IN2 | 1 (RTF) | 1.3 |  |  |  | 8.5 | 4 |
|  | IT-170GT |  | CORE |  | 6 | ±0.984 | 1080x2 | 3.89 |  |  |
| 5 |  |  | GND1 | 2 (RTF) | 2.6 |  |  |  |  |  |
|  | IT-170GT |  | PP |  | 6 | ±0.984 | Vendor Define | 3.89 |  |  |
| 6 |  |  | BOTTOM | 0.5+plating | 1.95 |  |  |  | 10.5 | 4 |
|  |  |  | Soldermask |  | 0.6 |  |  | 3.8 |  |  |
|  |  |  |  | Total | 63 | ±10% |  |  |  |  |
